# BASEBOARD_FAB2 (Tioga Pass) — schematic parts with pin connectivity, parts 1–159 of 4751; source: Cadence DE-HDL packaged netlist (pstxprt.dat, pstxnet.dat, pstchip.dat)

BT8G1  BATTERY  pkg PLCLF  page 196
C1A1  CAP  22UF 4V 20% X6S  pkg 0805LF  page 227 : 1 = PVDDQ_KLM ; 2 = GND
C1A2  SC1U10V2KX-4-GP  10%  pkg SMD-BCG6  page 227 : 1 = P5V_STBY ; 2 = GND
C1A4  CAP  10UF 16V 10% X7R  pkg 0805  page 197 : 1 = P12V_NVDIMM_KLM ; 2 = GND
C1A5  CAP_A  0.01UF 25V 10% X7R  pkg 0402V  page 87 : 1 = M_M_VREF ; 2 = GND
C1A6  CAP  1.0UF 16V 10% X6S  pkg 0402  page 227 : 1 = VR_PVDDQ_KLM_PH2_VCIN ; 2 = GND
C1A8  CAP  0.220UF 16V 10% X7R  pkg 0402  page 227 : 1 = VR_PVDDQ_KLM_PH2_BOOT ; 2 = VR_PVDDQ_KLM_PH2_PHASE
C1A9  CAP  1.0UF 16V 10% X6S  pkg 0402  page 227 : 1 = VR_FET_SW_P12V_STBY_PVDDQ_KLM ; 2 = GND
C1A10  CAP_A  0.1UF 16V 10% X7R  pkg 0402V  page 227 : 1 = VR_FET_SW_P12V_STBY_PVDDQ_KLM ; 2 = GND
C1A11  SC1U10V2KX-4-GP  10%  pkg SMD-BCG6  page 227 : 1 = P5V_STBY ; 2 = GND
C1A12  CAP  22UF 4V 20% X6S  pkg 0805LF  page 227 : 1 = PVDDQ_KLM ; 2 = GND
C1A13  CAP  0.22UF 16V 10% X7R  pkg 0402  page 227 : 1 = P5V_STBY ; 2 = GND
C1A16  CAP  10UF 16V 10% X7R  pkg 0805  page 197 : 1 = P12V_NVDIMM_KLM ; 2 = GND
C1A17  CAP_A  0.01UF 25V 10% X7R  pkg 0402V  page 86 : 1 = M_L_VREF ; 2 = GND
C1A18  CAP  0.220UF 16V 10% X7R  pkg 0402  page 227 : 1 = VR_PVDDQ_KLM_PH1_BOOT ; 2 = VR_PVDDQ_KLM_PH1_PHASE
C1A19  CAP  1.0UF 16V 10% X6S  pkg 0402  page 227 : 1 = VR_FET_SW_P12V_STBY_PVDDQ_KLM ; 2 = GND
C1A20  CAP_A  0.1UF 16V 10% X7R  pkg 0402V  page 227 : 1 = VR_FET_SW_P12V_STBY_PVDDQ_KLM ; 2 = GND
C1B2  CAP_A  0.1UF 16V 10% X7R  pkg 0402V  page 226 : 1 = VR_PVDDQ_KLM_VD12 ; 2 = GND
C1B3  CAP_A  1.0UF 6.3V 10% X6S  pkg 0402V  page 226 : 1 = VR_PVDDQ_KLM_VD12 ; 2 = GND
C1B4  CAP  1000PF 50V 10% X7R  pkg 0402LF  page 226 : 1 = PWRGD_PVDDQ_KLM_R ; 2 = GND
C1B5  CAP_A  0.1UF 16V 10% X7R  pkg 0402V  page 226 : 1 = VR_PVDDQ_KLM_VDD ; 2 = GND
C1B6  CAP_A  1.0UF 6.3V 10% X6S  pkg 0402V  page 226 : 1 = VR_PVDDQ_KLM_VDD ; 2 = GND
C1B7  CAP  10UF 16V 10% X7R  pkg 0805  page 197 : 1 = P12V_NVDIMM_KLM ; 2 = GND
C1B9  CAP_A  0.01UF 25V 10% X7R  pkg 0402V  page 83 : 1 = M_K_VREF ; 2 = GND
C1B10  CAPP  270UF 16V 20% OSCON  pkg 2626  page 228 : 1 = VR_FET_SW_P12V_STBY_PVDDQ_KLM ; 2 = GND
C1B11  CAP  220PF 50V 10% X7R  pkg 0402LF  page 226 : 1 = A_TSENSE_PVDDQ_KLM ; 2 = GND
C1B12  CAP  220PF 50V 10% X7R  pkg 0402LF  page 226 : 1 = VR_PVDDQ_KLM_AVSP ; 2 = VSENSE_PVDDQ_KLM_N
C1B14  CAPP  470UF 16V 20% ALUM  pkg 4040LF  page 195 : 1 = P12V_STBY ; 2 = GND
C1B15  CAP_A  0.01UF 25V 10% X7R  pkg 0402V  page 161 : 1 = FAN_TACH2 ; 2 = GND
C1B18  CAP  10UF 16V 10% X6S  pkg 0805  page 198 : 1 = P12V_FAN ; 2 = GND
C1B19  CAP_A  0.1UF 16V 10% X7R  pkg 0402V  page 198 : 1 = P12V_FAN ; 2 = GND
C1B20  CAP  1.0UF 16V 10% X6S  pkg 0402  page 227 : 1 = VR_PVDDQ_KLM_PH1_VCIN ; 2 = GND
C1B21  CAP  0.22UF 16V 10% X7R  pkg 0402  page 227 : 1 = P5V_STBY ; 2 = GND
C1C1  CAPP  270UF 16V 20% OSCON  pkg 2626  page 209 : 1 = VR_FET_SW_P12V_STBY_PVCCIN_CPU1 ; 2 = GND
C1C2  CAPP  270UF 16V 20% OSCON  pkg 2626  page 209 : 1 = VR_FET_SW_P12V_STBY_PVCCIN_CPU1 ; 2 = GND
C1C3  SC1U10V2KX-4-GP  10%  pkg SMD-BCG6  page 210 : 1 = P5V_STBY ; 2 = GND
C1C4  CAP  0.22UF 16V 10% X7R  pkg 0402  page 210 : 1 = P5V_STBY ; 2 = GND
C1C5  CAP  1.0UF 16V 10% X6S  pkg 0402  page 210 : 1 = VR_PVSA_CPU1_VCIN ; 2 = GND
C1C7  CAP_A  1.0UF 6.3V 10% X6S  pkg 0402V  page 206 : 1 = VR_PVCCIN_CPU1_VDD ; 2 = GND
C1C8  CAP_A  0.1UF 16V 10% X7R  pkg 0402V  page 206 : 1 = VR_PVCCIN_CPU1_AVINSEN ; 2 = GND
C1C9  CAP_A  0.1UF 16V 10% X7R  pkg 0402V  page 206 : 1 = VR_PVCCIN_CPU1_VDD ; 2 = GND
C1C10  CAP  220PF 50V 10% X7R  pkg 0402LF  page 206 : 1 = A_TSENSE_PVCCIN_CPU1 ; 2 = GND
C1C11  CAP  220PF 50V 10% X7R  pkg 0402LF  page 206 : 1 = A_TSENSE_PVSA_CPU1 ; 2 = GND
C1C12  CAP  0.220UF 16V 10% X7R  pkg 0402  page 210 : 1 = VR_PVSA_CPU1_BOOT ; 2 = VR_PVSA_CPU1_PHASE
C1C13  CAP_A  1.0UF 6.3V 10% X6S  pkg 0402V  page 206 : 1 = VR_PVCCIN_CPU1_VD12 ; 2 = GND
C1C14  CAP_A  0.1UF 16V 10% X7R  pkg 0402V  page 206 : 1 = VR_PVCCIN_CPU1_VD12 ; 2 = GND
C1C15  CAP  1.0UF 16V 10% X6S  pkg 0402  page 210 : 1 = VR_FET_SW_P12V_STBY_PVCCIN_CPU1 ; 2 = GND
C1C16  CAP  220PF 50V 10% X7R  pkg 0402LF  page 206 : 1 = VSENSE_PVSA_CPU1_BVSP ; 2 = VSENSE_PVSA_CPU1_N
C1C17  CAP_A  0.1UF 16V 10% X7R  pkg 0402V  page 210 : 1 = VR_FET_SW_P12V_STBY_PVCCIN_CPU1 ; 2 = GND
C1C18  SC1U10V2KX-4-GP  10%  pkg SMD-BCG6  page 209 : 1 = P5V_STBY ; 2 = GND
C1C19  CAP_A  22.0UF 4V 20% X6S  pkg 0603V  page 210 : 1 = PVSA_CPU1 ; 2 = GND
C1C23  CAP  1000PF 50V 10% X7R  pkg 0402LF  page 206 : 1 = VR_VRRDY_PVCCIN_CPU1 ; 2 = GND
C1C24  CAP  0.220UF 16V 10% X7R  pkg 0402  page 209 : 1 = VR_PVCCIN_CPU1_PH5_BOOT ; 2 = VR_PVCCIN_CPU1_PH5_PHASE
C1C25  CAP_A  0.1UF 16V 10% X7R  pkg 0402V  page 209 : 1 = VR_FET_SW_P12V_STBY_PVCCIN_CPU1 ; 2 = GND
C1C26  CAP  1.0UF 16V 10% X6S  pkg 0402  page 209 : 1 = VR_FET_SW_P12V_STBY_PVCCIN_CPU1 ; 2 = GND
C1D1  CAP  220PF 50V 10% X7R  pkg 0402LF  page 206 : 1 = VSENSE_PVCCIN_CPU1_AVSP ; 2 = VSENSE_PVCCIN_CPU1_N
C1D3  CAP_A  22.0UF 4V 20% X6S  pkg 0603V  page 208 : 1 = PVCCIN_CPU1 ; 2 = GND
C1D5  SC1U10V2KX-4-GP  10%  pkg SMD-BCG6  page 208 : 1 = P5V_STBY ; 2 = GND
C1D6  CAP  0.22UF 16V 10% X7R  pkg 0402  page 208 : 1 = P5V_STBY ; 2 = GND
C1D7  CAP  1.0UF 16V 10% X6S  pkg 0402  page 208 : 1 = VR_PVCCIN_CPU1_PH4_VCIN ; 2 = GND
C1D9  CAP_A  0.1UF 16V 10% X7R  pkg 0402V  page 200 : 1 = P12V_STBY ; 2 = AGND_HSC
C1D10  CAP  0.220UF 16V 10% X7R  pkg 0402  page 208 : 1 = VR_PVCCIN_CPU1_PH4_BOOT ; 2 = VR_PVCCIN_CPU1_PH4_PHASE
C1D11  CAP_A  0.1UF 16V 10% X7R  pkg 0402V  page 199 : 1 = FM_P12V_HOTSWAP0_EN ; 2 = AGND_HSC
C1D12  CAP  1.0UF 16V 10% X6S  pkg 0402  page 208 : 1 = VR_FET_SW_P12V_STBY_PVCCIN_CPU1 ; 2 = GND
C1D13  CAP_A  0.1UF 16V 10% X7R  pkg 0402V  page 208 : 1 = VR_FET_SW_P12V_STBY_PVCCIN_CPU1 ; 2 = GND
C1D14  CAP_A  22.0UF 4V 20% X6S  pkg 0603V  page 208 : 1 = PVCCIN_CPU1 ; 2 = GND
C1D15  SC1U10V2KX-4-GP  10%  pkg SMD-BCG6  page 208 : 1 = P5V_STBY ; 2 = GND
C1D16  CAP  0.22UF 16V 10% X7R  pkg 0402  page 208 : 1 = P5V_STBY ; 2 = GND
C1D17  CAP  1.0UF 16V 10% X6S  pkg 0402  page 208 : 1 = VR_PVCCIN_CPU1_PH3_VCIN ; 2 = GND
C1D19  CAP  1.0UF 16V 10% X6S  pkg 0402  page 199 : 1 = A_HSC_VCAP ; 2 = AGND_HSC
C1D20  CAP  0.220UF 16V 10% X7R  pkg 0402  page 208 : 1 = VR_PVCCIN_CPU1_PH3_BOOT ; 2 = VR_PVCCIN_CPU1_PH3_PHASE
C1D21  CAP_A  0.1UF 16V 10% X7R  pkg 0402V  page 199 : 1 = A_HSC_PSET ; 2 = AGND_HSC
C1D22  CAP_A  0.1UF 16V 10% EMPTY  pkg 0402V  page 200 : 1 = A_HSC_MON ; 2 = A_HSC_MOP
C1D23  CAP  1.0UF 16V 10% X6S  pkg 0402  page 208 : 1 = VR_FET_SW_P12V_STBY_PVCCIN_CPU1 ; 2 = GND
C1D24  CAP_A  22.0UF 4V 20% X6S  pkg 0603V  page 209 : 1 = PVCCIN_CPU1 ; 2 = GND
C1D25  CAP  1.0UF 16V 10% X6S  pkg 0402  page 199 : 1 = P12V_HSC_VCC ; 2 = AGND_HSC
C1D26  CAP_A  0.1UF 16V 10% X7R  pkg 0402V  page 199 : 1 = A_HSC_UV ; 2 = AGND_HSC
C1D27  CAP_A  0.1UF 16V 10% X7R  pkg 0402V  page 199 : 1 = A_HSC_OV ; 2 = AGND_HSC
C1D28  CAP_A  0.1UF 16V 10% X7R  pkg 0402V  page 208 : 1 = VR_FET_SW_P12V_STBY_PVCCIN_CPU1 ; 2 = GND
C1D32  CAP  1.0UF 16V 10% X6S  pkg 0402  page 209 : 1 = VR_PVCCIN_CPU1_PH5_VCIN ; 2 = GND
C1D33  CAP  0.22UF 16V 10% X7R  pkg 0402  page 209 : 1 = P5V_STBY ; 2 = GND
C1D34  CAP_A  0.1UF 16V 10% X7R  pkg 0402V  page 207 : 1 = VR_FET_SW_P12V_STBY_PVCCIN_CPU1 ; 2 = GND
C1D35  CAP  1.0UF 16V 10% X6S  pkg 0402  page 207 : 1 = VR_FET_SW_P12V_STBY_PVCCIN_CPU1 ; 2 = GND
C1D36  CAP  0.220UF 16V 10% X7R  pkg 0402  page 207 : 1 = VR_PVCCIN_CPU1_PH2_BOOT ; 2 = VR_PVCCIN_CPU1_PH2_PHASE
C1E2  CAP  0.068UF 50V 20% X7R  pkg 1206  page 200 : 1 = A_HSC_C ; 2 = GND
C1E3  CAP_A  22.0UF 4V 20% X6S  pkg 0603V  page 207 : 1 = PVCCIN_CPU1 ; 2 = GND
C1E6  SC1U10V2KX-4-GP  10%  pkg SMD-BCG6  page 207 : 1 = P5V_STBY ; 2 = GND
C1E7  CAP  0.22UF 16V 10% X7R  pkg 0402  page 207 : 1 = P5V_STBY ; 2 = GND
C1E8  CAP  1.0UF 16V 10% X6S  pkg 0402  page 207 : 1 = VR_PVCCIN_CPU1_PH1_VCIN ; 2 = GND
C1E9  CAP_A  22.0UF 4V 20% X6S  pkg 0603V  page 207 : 1 = PVCCIN_CPU1 ; 2 = GND
C1E11  CAP  0.220UF 16V 10% X7R  pkg 0402  page 207 : 1 = VR_PVCCIN_CPU1_PH1_BOOT ; 2 = VR_PVCCIN_CPU1_PH1_PHASE
C1E12  CAP  10UF 16V 10% X6S  pkg 0805  page 195 : 1 = P12V_PSU ; 2 = GND
C1E13  CAP  1.0UF 16V 10% X6S  pkg 0402  page 207 : 1 = VR_FET_SW_P12V_STBY_PVCCIN_CPU1 ; 2 = GND
C1E14  CAP_A  0.1UF 16V 10% X7R  pkg 0402V  page 207 : 1 = VR_FET_SW_P12V_STBY_PVCCIN_CPU1 ; 2 = GND
C1E15  CAP  10UF 16V 10% X6S  pkg 0805  page 195 : 1 = P12V_PSU ; 2 = GND
C1E16  CAP_A  0.1UF 16V 10% X7R  pkg 0402V  page 195 : 1 = P12V_PSU ; 2 = GND
C1E17  CAP_A  0.1UF 16V 10% X7R  pkg 0402V  page 195 : 1 = P12V_PSU ; 2 = GND
C1E18  CAPP  270UF 16V 20% OSCON  pkg 2626  page 209 : 1 = VR_FET_SW_P12V_STBY_PVCCIN_CPU1 ; 2 = GND
C1E19  CAP  47.0PF 50V 5% EMPTY  pkg 0402LF  page 167 : 1 = ISENSE_TMP421_2_DXP ; 2 = ISENSE_TMP421_2_DXN
C1E20  CAP_A  0.1UF 16V 10% X7R  pkg 0402V  page 161 : 1 = P12V_FAN ; 2 = GND
C1E21  CAP  10UF 16V 10% X6S  pkg 0805  page 161 : 1 = P12V_FAN ; 2 = GND
C1E22  CAP_A  0.1UF 16V 10% X7R  pkg 0402V  page 161 : 1 = P3V3_STBY ; 2 = GND
C1E23  SC1U10V2KX-4-GP  10%  pkg SMD-BCG6  page 207 : 1 = P5V_STBY ; 2 = GND
C1E24  CAP  1.0UF 16V 10% X6S  pkg 0402  page 207 : 1 = VR_PVCCIN_CPU1_PH2_VCIN ; 2 = GND
C1E25  CAP  0.22UF 16V 10% X7R  pkg 0402  page 207 : 1 = P5V_STBY ; 2 = GND
C1F2  CAP  0.22UF 16V 10% X7R  pkg 0402  page 181 : 1 = P3E_CPU1_PE3_MP_C_TXP<7> ; 2 = P3E_CPU1_PE3_MP_TXP<7>
C1F3  CAP  0.22UF 16V 10% X7R  pkg 0402  page 181 : 1 = P3E_CPU1_PE3_MP_C_TXN<7> ; 2 = P3E_CPU1_PE3_MP_TXN<7>
C1F4  CAP  0.22UF 16V 10% X7R  pkg 0402  page 181 : 1 = P3E_CPU1_PE3_MP_C_TXN<6> ; 2 = P3E_CPU1_PE3_MP_TXN<6>
C1F5  CAP  0.22UF 16V 10% X7R  pkg 0402  page 181 : 1 = P3E_CPU1_PE3_MP_C_TXP<6> ; 2 = P3E_CPU1_PE3_MP_TXP<6>
C1F6  CAP  0.22UF 16V 10% X7R  pkg 0402  page 181 : 1 = P3E_CPU1_PE3_MP_C_TXP<5> ; 2 = P3E_CPU1_PE3_MP_TXP<5>
C1F7  CAPP  470UF 16V 20% ALUM  pkg 4040LF  page 195 : 1 = P12V_STBY ; 2 = GND
C1F8  CAP  0.22UF 16V 10% X7R  pkg 0402  page 181 : 1 = P3E_CPU1_PE3_MP_C_TXN<5> ; 2 = P3E_CPU1_PE3_MP_TXN<5>
C1F9  CAP_A  0.01UF 25V 10% X7R  pkg 0402V  page 161 : 1 = FAN_TACH0 ; 2 = GND
C1F10  CAP  0.22UF 16V 10% X7R  pkg 0402  page 181 : 1 = P3E_CPU1_PE3_MP_C_TXN<4> ; 2 = P3E_CPU1_PE3_MP_TXN<4>
C1F11  CAP  0.22UF 16V 10% X7R  pkg 0402  page 181 : 1 = P3E_CPU1_PE3_MP_C_TXP<4> ; 2 = P3E_CPU1_PE3_MP_TXP<4>
C1F12  CAP  0.22UF 16V 10% X7R  pkg 0402  page 181 : 1 = P3E_CPU1_PE3_MP_C_TXP<3> ; 2 = P3E_CPU1_PE3_MP_TXP<3>
C1F13  CAP  0.22UF 16V 10% X7R  pkg 0402  page 181 : 1 = P3E_CPU1_PE3_MP_C_TXN<3> ; 2 = P3E_CPU1_PE3_MP_TXN<3>
C1F14  CAP  0.22UF 16V 10% X7R  pkg 0402  page 181 : 1 = P3E_CPU1_PE3_MP_C_TXP<2> ; 2 = P3E_CPU1_PE3_MP_TXP<2>
C1F15  CAP  0.22UF 16V 10% X7R  pkg 0402  page 181 : 1 = P3E_CPU1_PE3_MP_C_TXN<2> ; 2 = P3E_CPU1_PE3_MP_TXN<2>
C1F16  CAP  0.22UF 16V 10% X7R  pkg 0402  page 181 : 1 = P3E_CPU1_PE3_MP_C_TXN<1> ; 2 = P3E_CPU1_PE3_MP_TXN<1>
C1F17  CAP  0.22UF 16V 10% X7R  pkg 0402  page 181 : 1 = P3E_CPU1_PE3_MP_C_TXP<1> ; 2 = P3E_CPU1_PE3_MP_TXP<1>
C1F18  CAP  0.22UF 16V 10% X7R  pkg 0402  page 181 : 1 = P3E_CPU1_PE3_MP_C_TXP<0> ; 2 = P3E_CPU1_PE3_MP_TXP<0>
C1F19  CAP_A  0.01UF 25V 10% X7R  pkg 0402V  page 100 : 1 = M_G_CPU_VREF ; 2 = GND
C1F20  CAP  0.22UF 16V 10% X7R  pkg 0402  page 181 : 1 = P3E_CPU1_PE3_MP_C_TXN<0> ; 2 = P3E_CPU1_PE3_MP_TXN<0>
C1F21  SC1U10V2KX-4-GP  10%  pkg SMD-BCG6  page 224 : 1 = P5V_STBY ; 2 = GND
C1F22  CAP_A  0.01UF 25V 10% X7R  pkg 0402V  page 77 : 1 = M_G_VREF ; 2 = GND
C1F26  CAP  0.220UF 16V 10% X7R  pkg 0402  page 224 : 1 = VR_PVDDQ_GHJ_PH2_BOOT ; 2 = VR_PVDDQ_GHJ_PH2_PHASE
C1F27  CAP  1.0UF 16V 10% X6S  pkg 0402  page 224 : 1 = VR_FET_SW_P12V_STBY_PVDDQ_GHJ ; 2 = GND
C1F28  CAP_A  0.1UF 16V 10% X7R  pkg 0402V  page 224 : 1 = VR_FET_SW_P12V_STBY_PVDDQ_GHJ ; 2 = GND
C1G2  SC22U16V5MX-4-GP  20%  pkg SMD-BCG5  page 225 : 1 = VR_FET_SW_P12V_STBY_PVDDQ_GHJ ; 2 = GND
C1G4  SC1U10V2KX-4-GP  10%  pkg SMD-BCG6  page 224 : 1 = P5V_STBY ; 2 = GND
C1G5  CAP  0.22UF 16V 10% X7R  pkg 0402  page 224 : 1 = P5V_STBY ; 2 = GND
C1G6  CAP  1.0UF 16V 10% X6S  pkg 0402  page 224 : 1 = VR_PVDDQ_GHJ_PH1_VCIN ; 2 = GND
C1G7  ST270U2D5VBM-GP  pkg SMD-TCG2  page 225 : 1 = VR_FET_SW_P12V_STBY_PVDDQ_GHJ ; 2 = GND
C1G8  CAP_A  0.01UF 25V 10% X7R  pkg 0402V  page 100 : 1 = M_H_CPU_VREF ; 2 = GND
C1G10  CAP_A  0.01UF 25V 10% X7R  pkg 0402V  page 80 : 1 = M_H_VREF ; 2 = GND
C1G11  CAP  0.220UF 16V 10% X7R  pkg 0402  page 224 : 1 = VR_PVDDQ_GHJ_PH1_BOOT ; 2 = VR_PVDDQ_GHJ_PH1_PHASE
C1G12  ST270U2D5VBM-GP  pkg SMD-TCG2  page 225 : 1 = VR_FET_SW_P12V_STBY_PVDDQ_GHJ ; 2 = GND
C1G13  CAP  1.0UF 16V 10% X6S  pkg 0402  page 224 : 1 = VR_FET_SW_P12V_STBY_PVDDQ_GHJ ; 2 = GND
C1G14  CAP_A  0.1UF 16V 10% X7R  pkg 0402V  page 224 : 1 = VR_FET_SW_P12V_STBY_PVDDQ_GHJ ; 2 = GND
C1G15  ST270U2D5VBM-GP  pkg SMD-TCG2  page 225 : 1 = VR_FET_SW_P12V_STBY_PVDDQ_GHJ ; 2 = GND
C1G16  CAP  220PF 50V 10% X7R  pkg 0402LF  page 223 : 1 = VR_PVDDQ_GHJ_AVSP ; 2 = VSENSE_PVDDQ_GHJ_N
C1G17  CAP  22UF 4V 20% X6S  pkg 0805LF  page 224 : 1 = PVDDQ_GHJ ; 2 = GND
C1G18  CAP_A  0.01UF 25V 10% X7R  pkg 0402V  page 100 : 1 = M_J_CPU_VREF ; 2 = GND
C1G19  CAP_A  0.01UF 25V 10% X7R  pkg 0402V  page 82 : 1 = M_J_VREF ; 2 = GND
C1G20  CAP  22UF 4V 20% X6S  pkg 0805LF  page 224 : 1 = PVDDQ_GHJ ; 2 = GND
C1G21  CAP  1000PF 50V 10% X7R  pkg 0402LF  page 223 : 1 = PWRGD_PVDDQ_GHJ_R ; 2 = GND
C1G22  CAP_A  0.1UF 16V 10% X7R  pkg 0402V  page 223 : 1 = VR_PVDDQ_GHJ_VD12 ; 2 = GND
C1G23  CAP_A  1.0UF 6.3V 10% X6S  pkg 0402V  page 223 : 1 = VR_PVDDQ_GHJ_VD12 ; 2 = GND
C1G24  CAP  220PF 50V 10% X7R  pkg 0402LF  page 223 : 1 = A_TSENSE_PVDDQ_GHJ ; 2 = GND
C1G25  CAP_A  0.1UF 16V 10% X7R  pkg 0402V  page 223 : 1 = VR_PVDDQ_GHJ_VDD ; 2 = GND
C1G27  CAP_A  1.0UF 6.3V 10% X6S  pkg 0402V  page 223 : 1 = VR_PVDDQ_GHJ_VDD ; 2 = GND
C1G28  CAP  1.0UF 16V 10% X6S  pkg 0402  page 224 : 1 = VR_PVDDQ_GHJ_PH2_VCIN ; 2 = GND
C1G29  CAP  0.22UF 16V 10% X7R  pkg 0402  page 224 : 1 = P5V_STBY ; 2 = GND
C1L1  CAP  1.0UF 16V 10% X6S  pkg 0402  page 112 : 1 = P3V3_STBY ; 2 = GND
C1L4  CAP_A  0.1UF 16V 10% X7R  pkg 0402V  page 175 : 1 = P5V_STBY ; 2 = GND
C1L5  CAP_A  1.0UF 6.3V 10% X6S  pkg 0402V  page 111 : 1 = P1V05_PCH_STBY ; 2 = GND
C1L8  CAP_A  0.1UF 16V 10% X7R  pkg 0402V  page 111 : 1 = XDP_PWRGD_RST_N ; 2 = GND
C1L9  CAP_A  0.1UF 16V 10% X7R  pkg 0402V  page 175 : 1 = P3V3_STBY ; 2 = GND
